(kicad_pcb
	(version 20260206)
	(generator "pcbnew")
	(generator_version "10.0")
	(general
		(thickness 1.6)
		(legacy_teardrops no)
	)
	(paper "A4")
	(title_block
		(title "04192023_DAF0TMB3IC0_F0TG_MB_C_brd_V02_OCP.brd")
		(comment 1 "Grand Teton / footprints 6041-6048 of 8354")
	)
	(layers
		(0 "F.Cu" signal "TOP")
		(4 "In1.Cu" signal "GND")
		(6 "In2.Cu" signal "IN1")
		(8 "In3.Cu" signal "GND1")
		(10 "In4.Cu" signal "IN2")
		(12 "In5.Cu" signal "GND2")
		(14 "In6.Cu" signal "IN3")
		(16 "In7.Cu" signal "GND3")
		(18 "In8.Cu" signal "VCC")
		(20 "In9.Cu" signal "VCC1")
		(22 "In10.Cu" signal "GND4")
		(24 "In11.Cu" signal "IN4")
		(26 "In12.Cu" signal "GND5")
		(28 "In13.Cu" signal "IN5")
		(30 "In14.Cu" signal "GND6")
		(32 "In15.Cu" signal "IN6")
		(34 "In16.Cu" signal "GND7")
		(2 "B.Cu" signal "BOTTOM")
		(9 "F.Adhes" user "F.Adhesive")
		(11 "B.Adhes" user "B.Adhesive")
		(13 "F.Paste" user "Package Geometry/Pastemask Top")
		(15 "B.Paste" user "Package Geometry/Pastemask Bottom")
		(5 "F.SilkS" user "Ref Des/Silkscreen Top")
		(7 "B.SilkS" user "Ref Des/Silkscreen Bottom")
		(1 "F.Mask" user "Board Geometry/Soldermask Top")
		(3 "B.Mask" user "Board Geometry/Soldermask Bottom")
		(17 "Dwgs.User" user "User.Drawings")
		(19 "Cmts.User" user "User.Comments")
		(21 "Eco1.User" user "User.Eco1")
		(23 "Eco2.User" user "User.Eco2")
		(25 "Edge.Cuts" user "Board Geometry/Outline")
		(27 "Margin" user)
		(31 "F.CrtYd" user "Package Geometry/Place Bound Top")
		(29 "B.CrtYd" user "Package Geometry/Place Bound Bottom")
		(35 "F.Fab" user "Ref Des/Assembly Top")
		(33 "B.Fab" user "Ref Des/Assembly Bottom")
	)
	(footprint ""
		(layer "B.Cu")
		(at 326.052942 -391.2616 180)
		(property "Reference" "R6821"
			(at 0 0 0)
			(layer "B.SilkS")
			(hide yes)
			(effects
				(font
					(size 1.27 1.27)
				)
				(justify mirror)
			)
		)
		(property "Value" ""
			(at 0 0 0)
			(layer "B.Fab")
			(effects
				(font
					(size 1.27 1.27)
				)
				(justify mirror)
			)
		)
		(duplicate_pad_numbers_are_jumpers no)
		(fp_line
			(start 0.32512 0.175006)
			(end 0.32512 -0.175006)
			(stroke
				(width 0.1)
				(type default)
			)
			(layer "B.Fab")
		)
		(fp_line
			(start 0.32512 -0.175006)
			(end -0.32512 -0.175006)
			(stroke
				(width 0.1)
				(type default)
			)
			(layer "B.Fab")
		)
		(fp_line
			(start -0.32512 0.175006)
			(end 0.32512 0.175006)
			(stroke
				(width 0.1)
				(type default)
			)
			(layer "B.Fab")
		)
		(fp_line
			(start -0.32512 -0.175006)
			(end -0.32512 0.175006)
			(stroke
				(width 0.1)
				(type default)
			)
			(layer "B.Fab")
		)
		(pad "1" smd rect
			(at 0.2667 0)
			(size 0.3048 0.381)
			(layers "B.Cu" "B.Mask" "B.Paste")
			(net "NCF_CPU0_P0_GND")
		)
		(pad "2" smd rect
			(at -0.2667 0 180)
			(size 0.3048 0.381)
			(layers "B.Cu" "B.Mask" "B.Paste")
			(net "GND")
		)
	)
	(footprint ""
		(layer "B.Cu")
		(at 416.346132 -396.393162 -90)
		(property "Reference" "C794"
			(at 0 0 90)
			(layer "B.SilkS")
			(hide yes)
			(effects
				(font
					(size 1.27 1.27)
				)
				(justify mirror)
			)
		)
		(property "Value" ""
			(at 0 0 90)
			(layer "B.Fab")
			(effects
				(font
					(size 1.27 1.27)
				)
				(justify mirror)
			)
		)
		(duplicate_pad_numbers_are_jumpers no)
		(fp_line
			(start -0.299974 0.150114)
			(end 0.299974 0.150114)
			(stroke
				(width 0.1)
				(type default)
			)
			(layer "B.Fab")
		)
		(fp_line
			(start 0.299974 0.150114)
			(end 0.299974 -0.150114)
			(stroke
				(width 0.1)
				(type default)
			)
			(layer "B.Fab")
		)
		(fp_line
			(start -0.299974 -0.150114)
			(end -0.299974 0.150114)
			(stroke
				(width 0.1)
				(type default)
			)
			(layer "B.Fab")
		)
		(fp_line
			(start 0.299974 -0.150114)
			(end -0.299974 -0.150114)
			(stroke
				(width 0.1)
				(type default)
			)
			(layer "B.Fab")
		)
		(pad "1" smd rect
			(at 0.2667 0 90)
			(size 0.3048 0.381)
			(layers "B.Cu" "B.Mask" "B.Paste")
			(net "P0V9_CPU0_RT2_2A_2D")
		)
		(pad "2" smd rect
			(at -0.2667 0 90)
			(size 0.3048 0.381)
			(layers "B.Cu" "B.Mask" "B.Paste")
			(net "GND")
		)
	)
	(footprint ""
		(layer "B.Cu")
		(at 449.646802 -425.92371)
		(property "Reference" "PR6606"
			(at 0 0 0)
			(layer "B.SilkS")
			(hide yes)
			(effects
				(font
					(size 1.27 1.27)
				)
				(justify mirror)
			)
		)
		(property "Value" ""
			(at 0 0 0)
			(layer "B.Fab")
			(effects
				(font
					(size 1.27 1.27)
				)
				(justify mirror)
			)
		)
		(duplicate_pad_numbers_are_jumpers no)
		(fp_line
			(start -0.7874 -0.4064)
			(end -0.7874 0.4064)
			(stroke
				(width 0.1524)
				(type default)
			)
			(layer "B.SilkS")
		)
		(fp_line
			(start -0.7874 0.4064)
			(end 0.7874 0.4064)
			(stroke
				(width 0.1524)
				(type default)
			)
			(layer "B.SilkS")
		)
		(fp_line
			(start 0.7874 -0.4064)
			(end -0.7874 -0.4064)
			(stroke
				(width 0.1524)
				(type default)
			)
			(layer "B.SilkS")
		)
		(fp_line
			(start 0.7874 0.4064)
			(end 0.7874 -0.4064)
			(stroke
				(width 0.1524)
				(type default)
			)
			(layer "B.SilkS")
		)
		(fp_line
			(start -0.67945 -0.3048)
			(end -0.67945 0.3048)
			(stroke
				(width 0.1)
				(type default)
			)
			(layer "B.Fab")
		)
		(fp_line
			(start -0.67945 0.3048)
			(end -0.120396 0.3048)
			(stroke
				(width 0.1)
				(type default)
			)
			(layer "B.Fab")
		)
		(fp_line
			(start -0.12065 -0.3048)
			(end -0.67945 -0.3048)
			(stroke
				(width 0.1)
				(type default)
			)
			(layer "B.Fab")
		)
		(fp_line
			(start -0.12065 -0.2794)
			(end -0.12065 -0.3048)
			(stroke
				(width 0.1)
				(type default)
			)
			(layer "B.Fab")
		)
		(fp_line
			(start -0.120396 0.2794)
			(end 0.12065 0.2794)
			(stroke
				(width 0.1)
				(type default)
			)
			(layer "B.Fab")
		)
		(fp_line
			(start -0.120396 0.3048)
			(end -0.120396 0.2794)
			(stroke
				(width 0.1)
				(type default)
			)
			(layer "B.Fab")
		)
		(fp_line
			(start 0.12065 -0.305054)
			(end 0.12065 -0.2794)
			(stroke
				(width 0.1)
				(type default)
			)
			(layer "B.Fab")
		)
		(fp_line
			(start 0.12065 -0.2794)
			(end -0.12065 -0.2794)
			(stroke
				(width 0.1)
				(type default)
			)
			(layer "B.Fab")
		)
		(fp_line
			(start 0.12065 0.2794)
			(end 0.12065 0.3048)
			(stroke
				(width 0.1)
				(type default)
			)
			(layer "B.Fab")
		)
		(fp_line
			(start 0.12065 0.3048)
			(end 0.67945 0.3048)
			(stroke
				(width 0.1)
				(type default)
			)
			(layer "B.Fab")
		)
		(fp_line
			(start 0.67945 -0.305054)
			(end 0.12065 -0.305054)
			(stroke
				(width 0.1)
				(type default)
			)
			(layer "B.Fab")
		)
		(fp_line
			(start 0.67945 0.3048)
			(end 0.67945 -0.305054)
			(stroke
				(width 0.1)
				(type default)
			)
			(layer "B.Fab")
		)
		(pad "1" smd circle
			(at 0.40005 0 180)
			(size 0 0)
			(layers "B.Cu" "B.Mask" "B.Paste")
			(net "P12V_AUX")
		)
		(pad "2" smd circle
			(at -0.40005 0 180)
			(size 0 0)
			(layers "B.Cu" "B.Mask" "B.Paste")
			(net "P0V9_RETIMER_CPU0_VINSEN")
		)
	)
	(footprint ""
		(layer "B.Cu")
		(at 339.910166 -416.899344 90)
		(property "Reference" "C6555"
			(at 0 0 90)
			(layer "B.SilkS")
			(hide yes)
			(effects
				(font
					(size 1.27 1.27)
				)
				(justify mirror)
			)
		)
		(property "Value" ""
			(at 0 0 90)
			(layer "B.Fab")
			(effects
				(font
					(size 1.27 1.27)
				)
				(justify mirror)
			)
		)
		(duplicate_pad_numbers_are_jumpers no)
		(fp_line
			(start 0.299974 -0.150114)
			(end -0.299974 -0.150114)
			(stroke
				(width 0.1)
				(type default)
			)
			(layer "B.Fab")
		)
		(fp_line
			(start -0.299974 -0.150114)
			(end -0.299974 0.150114)
			(stroke
				(width 0.1)
				(type default)
			)
			(layer "B.Fab")
		)
		(fp_line
			(start 0.299974 0.150114)
			(end 0.299974 -0.150114)
			(stroke
				(width 0.1)
				(type default)
			)
			(layer "B.Fab")
		)
		(fp_line
			(start -0.299974 0.150114)
			(end 0.299974 0.150114)
			(stroke
				(width 0.1)
				(type default)
			)
			(layer "B.Fab")
		)
		(pad "1" smd rect
			(at 0.2667 0 270)
			(size 0.3048 0.381)
			(layers "B.Cu" "B.Mask" "B.Paste")
			(net "P5E_CPU0_P1_TX_BUF_C_DP<11>")
		)
		(pad "2" smd rect
			(at -0.2667 0 270)
			(size 0.3048 0.381)
			(layers "B.Cu" "B.Mask" "B.Paste")
			(net "P5E_CPU0_P1_TX_BUF_DP<11>")
		)
	)
	(footprint ""
		(layer "B.Cu")
		(at 226.366578 -290.844732 180)
		(property "Reference" "R644"
			(at 0 0 0)
			(layer "B.SilkS")
			(hide yes)
			(effects
				(font
					(size 1.27 1.27)
				)
				(justify mirror)
			)
		)
		(property "Value" ""
			(at 0 0 0)
			(layer "B.Fab")
			(effects
				(font
					(size 1.27 1.27)
				)
				(justify mirror)
			)
		)
		(duplicate_pad_numbers_are_jumpers no)
		(fp_line
			(start 0.7874 0.4064)
			(end 0.7874 -0.4064)
			(stroke
				(width 0.1524)
				(type default)
			)
			(layer "B.SilkS")
		)
		(fp_line
			(start 0.7874 -0.4064)
			(end -0.7874 -0.4064)
			(stroke
				(width 0.1524)
				(type default)
			)
			(layer "B.SilkS")
		)
		(fp_line
			(start -0.7874 0.4064)
			(end 0.7874 0.4064)
			(stroke
				(width 0.1524)
				(type default)
			)
			(layer "B.SilkS")
		)
		(fp_line
			(start -0.7874 -0.4064)
			(end -0.7874 0.4064)
			(stroke
				(width 0.1524)
				(type default)
			)
			(layer "B.SilkS")
		)
		(fp_line
			(start 0.67945 0.3048)
			(end 0.67945 -0.305054)
			(stroke
				(width 0.1)
				(type default)
			)
			(layer "B.Fab")
		)
		(fp_line
			(start 0.67945 -0.305054)
			(end 0.12065 -0.305054)
			(stroke
				(width 0.1)
				(type default)
			)
			(layer "B.Fab")
		)
		(fp_line
			(start 0.12065 0.3048)
			(end 0.67945 0.3048)
			(stroke
				(width 0.1)
				(type default)
			)
			(layer "B.Fab")
		)
		(fp_line
			(start 0.12065 0.2794)
			(end 0.12065 0.3048)
			(stroke
				(width 0.1)
				(type default)
			)
			(layer "B.Fab")
		)
		(fp_line
			(start 0.12065 -0.2794)
			(end -0.12065 -0.2794)
			(stroke
				(width 0.1)
				(type default)
			)
			(layer "B.Fab")
		)
		(fp_line
			(start 0.12065 -0.305054)
			(end 0.12065 -0.2794)
			(stroke
				(width 0.1)
				(type default)
			)
			(layer "B.Fab")
		)
		(fp_line
			(start -0.120396 0.3048)
			(end -0.120396 0.2794)
			(stroke
				(width 0.1)
				(type default)
			)
			(layer "B.Fab")
		)
		(fp_line
			(start -0.120396 0.2794)
			(end 0.12065 0.2794)
			(stroke
				(width 0.1)
				(type default)
			)
			(layer "B.Fab")
		)
		(fp_line
			(start -0.12065 -0.2794)
			(end -0.12065 -0.3048)
			(stroke
				(width 0.1)
				(type default)
			)
			(layer "B.Fab")
		)
		(fp_line
			(start -0.12065 -0.3048)
			(end -0.67945 -0.3048)
			(stroke
				(width 0.1)
				(type default)
			)
			(layer "B.Fab")
		)
		(fp_line
			(start -0.67945 0.3048)
			(end -0.120396 0.3048)
			(stroke
				(width 0.1)
				(type default)
			)
			(layer "B.Fab")
		)
		(fp_line
			(start -0.67945 -0.3048)
			(end -0.67945 0.3048)
			(stroke
				(width 0.1)
				(type default)
			)
			(layer "B.Fab")
		)
		(pad "1" smd circle
			(at 0.40005 0)
			(size 0 0)
			(layers "B.Cu" "B.Mask" "B.Paste")
			(net "P3V3_AUX")
		)
		(pad "2" smd circle
			(at -0.40005 0)
			(size 0 0)
			(layers "B.Cu" "B.Mask" "B.Paste")
			(net "PWRGD_P1V8_RETIMER_CPU1")
		)
	)
	(footprint ""
		(layer "B.Cu")
		(at 55.791354 -390.560052 90)
		(property "Reference" "C121"
			(at 0 0 90)
			(layer "B.SilkS")
			(hide yes)
			(effects
				(font
					(size 1.27 1.27)
				)
				(justify mirror)
			)
		)
		(property "Value" ""
			(at 0 0 90)
			(layer "B.Fab")
			(effects
				(font
					(size 1.27 1.27)
				)
				(justify mirror)
			)
		)
		(duplicate_pad_numbers_are_jumpers no)
		(fp_line
			(start 0.7874 -0.4064)
			(end -0.7874 -0.4064)
			(stroke
				(width 0.1524)
				(type default)
			)
			(layer "B.SilkS")
		)
		(fp_line
			(start -0.7874 -0.4064)
			(end -0.7874 0.4064)
			(stroke
				(width 0.1524)
				(type default)
			)
			(layer "B.SilkS")
		)
		(fp_line
			(start 0.7874 0.4064)
			(end 0.7874 -0.4064)
			(stroke
				(width 0.1524)
				(type default)
			)
			(layer "B.SilkS")
		)
		(fp_line
			(start -0.7874 0.4064)
			(end 0.7874 0.4064)
			(stroke
				(width 0.1524)
				(type default)
			)
			(layer "B.SilkS")
		)
		(fp_line
			(start 0.67945 -0.305054)
			(end 0.12065 -0.305054)
			(stroke
				(width 0.1)
				(type default)
			)
			(layer "B.Fab")
		)
		(fp_line
			(start 0.12065 -0.305054)
			(end 0.12065 -0.2794)
			(stroke
				(width 0.1)
				(type default)
			)
			(layer "B.Fab")
		)
		(fp_line
			(start -0.12065 -0.3048)
			(end -0.67945 -0.3048)
			(stroke
				(width 0.1)
				(type default)
			)
			(layer "B.Fab")
		)
		(fp_line
			(start -0.67945 -0.3048)
			(end -0.67945 0.3048)
			(stroke
				(width 0.1)
				(type default)
			)
			(layer "B.Fab")
		)
		(fp_line
			(start 0.12065 -0.2794)
			(end -0.12065 -0.2794)
			(stroke
				(width 0.1)
				(type default)
			)
			(layer "B.Fab")
		)
		(fp_line
			(start -0.12065 -0.2794)
			(end -0.12065 -0.3048)
			(stroke
				(width 0.1)
				(type default)
			)
			(layer "B.Fab")
		)
		(fp_line
			(start 0.12065 0.2794)
			(end 0.12065 0.3048)
			(stroke
				(width 0.1)
				(type default)
			)
			(layer "B.Fab")
		)
		(fp_line
			(start -0.120396 0.2794)
			(end 0.12065 0.2794)
			(stroke
				(width 0.1)
				(type default)
			)
			(layer "B.Fab")
		)
		(fp_line
			(start 0.67945 0.3048)
			(end 0.67945 -0.305054)
			(stroke
				(width 0.1)
				(type default)
			)
			(layer "B.Fab")
		)
		(fp_line
			(start 0.12065 0.3048)
			(end 0.67945 0.3048)
			(stroke
				(width 0.1)
				(type default)
			)
			(layer "B.Fab")
		)
		(fp_line
			(start -0.120396 0.3048)
			(end -0.120396 0.2794)
			(stroke
				(width 0.1)
				(type default)
			)
			(layer "B.Fab")
		)
		(fp_line
			(start -0.67945 0.3048)
			(end -0.120396 0.3048)
			(stroke
				(width 0.1)
				(type default)
			)
			(layer "B.Fab")
		)
		(pad "1" smd circle
			(at 0.40005 0 270)
			(size 0 0)
			(layers "B.Cu" "B.Mask" "B.Paste")
			(net "P1V8_CPU1_RT0_1A")
		)
		(pad "2" smd circle
			(at -0.40005 0 270)
			(size 0 0)
			(layers "B.Cu" "B.Mask" "B.Paste")
			(net "GND")
		)
	)
	(footprint ""
		(layer "B.Cu")
		(at 317.778384 -395.148562 90)
		(property "Reference" "C529"
			(at 0 0 90)
			(layer "B.SilkS")
			(hide yes)
			(effects
				(font
					(size 1.27 1.27)
				)
				(justify mirror)
			)
		)
		(property "Value" ""
			(at 0 0 90)
			(layer "B.Fab")
			(effects
				(font
					(size 1.27 1.27)
				)
				(justify mirror)
			)
		)
		(duplicate_pad_numbers_are_jumpers no)
		(fp_line
			(start 0.299974 -0.150114)
			(end -0.299974 -0.150114)
			(stroke
				(width 0.1)
				(type default)
			)
			(layer "B.Fab")
		)
		(fp_line
			(start -0.299974 -0.150114)
			(end -0.299974 0.150114)
			(stroke
				(width 0.1)
				(type default)
			)
			(layer "B.Fab")
		)
		(fp_line
			(start 0.299974 0.150114)
			(end 0.299974 -0.150114)
			(stroke
				(width 0.1)
				(type default)
			)
			(layer "B.Fab")
		)
		(fp_line
			(start -0.299974 0.150114)
			(end 0.299974 0.150114)
			(stroke
				(width 0.1)
				(type default)
			)
			(layer "B.Fab")
		)
		(pad "1" smd rect
			(at 0.2667 0 270)
			(size 0.3048 0.381)
			(layers "B.Cu" "B.Mask" "B.Paste")
			(net "P0V9_CPU0_RT0_2A")
		)
		(pad "2" smd rect
			(at -0.2667 0 270)
			(size 0.3048 0.381)
			(layers "B.Cu" "B.Mask" "B.Paste")
			(net "GND")
		)
	)
	(footprint ""
		(layer "B.Cu")
		(at 116.527834 -245.487952)
		(property "Reference" "C2306"
			(at 0 0 0)
			(layer "B.SilkS")
			(hide yes)
			(effects
				(font
					(size 1.27 1.27)
				)
				(justify mirror)
			)
		)
		(property "Value" ""
			(at 0 0 0)
			(layer "B.Fab")
			(effects
				(font
					(size 1.27 1.27)
				)
				(justify mirror)
			)
		)
		(duplicate_pad_numbers_are_jumpers no)
		(fp_line
			(start -0.7874 -0.4064)
			(end -0.7874 0.4064)
			(stroke
				(width 0.1524)
				(type default)
			)
			(layer "B.SilkS")
		)
		(fp_line
			(start -0.7874 0.4064)
			(end 0.7874 0.4064)
			(stroke
				(width 0.1524)
				(type default)
			)
			(layer "B.SilkS")
		)
		(fp_line
			(start 0.7874 -0.4064)
			(end -0.7874 -0.4064)
			(stroke
				(width 0.1524)
				(type default)
			)
			(layer "B.SilkS")
		)
		(fp_line
			(start 0.7874 0.4064)
			(end 0.7874 -0.4064)
			(stroke
				(width 0.1524)
				(type default)
			)
			(layer "B.SilkS")
		)
		(fp_line
			(start -0.67945 -0.3048)
			(end -0.67945 0.3048)
			(stroke
				(width 0.1)
				(type default)
			)
			(layer "B.Fab")
		)
		(fp_line
			(start -0.67945 0.3048)
			(end -0.120396 0.3048)
			(stroke
				(width 0.1)
				(type default)
			)
			(layer "B.Fab")
		)
		(fp_line
			(start -0.12065 -0.3048)
			(end -0.67945 -0.3048)
			(stroke
				(width 0.1)
				(type default)
			)
			(layer "B.Fab")
		)
		(fp_line
			(start -0.12065 -0.2794)
			(end -0.12065 -0.3048)
			(stroke
				(width 0.1)
				(type default)
			)
			(layer "B.Fab")
		)
		(fp_line
			(start -0.120396 0.2794)
			(end 0.12065 0.2794)
			(stroke
				(width 0.1)
				(type default)
			)
			(layer "B.Fab")
		)
		(fp_line
			(start -0.120396 0.3048)
			(end -0.120396 0.2794)
			(stroke
				(width 0.1)
				(type default)
			)
			(layer "B.Fab")
		)
		(fp_line
			(start 0.12065 -0.305054)
			(end 0.12065 -0.2794)
			(stroke
				(width 0.1)
				(type default)
			)
			(layer "B.Fab")
		)
		(fp_line
			(start 0.12065 -0.2794)
			(end -0.12065 -0.2794)
			(stroke
				(width 0.1)
				(type default)
			)
			(layer "B.Fab")
		)
		(fp_line
			(start 0.12065 0.2794)
			(end 0.12065 0.3048)
			(stroke
				(width 0.1)
				(type default)
			)
			(layer "B.Fab")
		)
		(fp_line
			(start 0.12065 0.3048)
			(end 0.67945 0.3048)
			(stroke
				(width 0.1)
				(type default)
			)
			(layer "B.Fab")
		)
		(fp_line
			(start 0.67945 -0.305054)
			(end 0.12065 -0.305054)
			(stroke
				(width 0.1)
				(type default)
			)
			(layer "B.Fab")
		)
		(fp_line
			(start 0.67945 0.3048)
			(end 0.67945 -0.305054)
			(stroke
				(width 0.1)
				(type default)
			)
			(layer "B.Fab")
		)
		(pad "1" smd circle
			(at 0.40005 0 180)
			(size 0 0)
			(layers "B.Cu" "B.Mask" "B.Paste")
			(net "PVDDCR_CPU0_P1")
		)
		(pad "2" smd circle
			(at -0.40005 0 180)
			(size 0 0)
			(layers "B.Cu" "B.Mask" "B.Paste")
			(net "GND")
		)
	)
)
